# S9S_MB_2U (Grand Teton) — schematic netlist excerpt (pin names and nets, part order shuffled) for the footprints in the layout excerpt that follows; sources: Cadence DE-HDL packaged netlist, KiCad conversion of 03242023_DA0F0TMBIJ0_F0T_Motherboard_J_brd_V01_OCP.brd

C5234  Q_CAP  0.1UF 25V 10% EMPTY  pkg 0402  page 152 : A = P3V3_AUX ; B = GND
C1251  Q_CAP  10UF 6.3V 20% X6S  pkg C0603  page 189 : A = P1V05_PCH_PLL_AUX ; B = GND

(kicad_pcb
	(version 20260206)
	(generator "pcbnew")
	(generator_version "10.0")
	(general
		(thickness 1.6)
		(legacy_teardrops no)
	)
	(paper "A4")
	(title_block
		(title "03242023_DA0F0TMBIJ0_F0T_Motherboard_J_brd_V01_OCP.brd")
		(comment 1 "Grand Teton / footprints 4216-4217 of 6105")
	)
	(layers
		(0 "F.Cu" signal "TOP")
		(4 "In1.Cu" signal "GND")
		(6 "In2.Cu" signal "IN1")
		(8 "In3.Cu" signal "GND1")
		(10 "In4.Cu" signal "IN2")
		(12 "In5.Cu" signal "GND2")
		(14 "In6.Cu" signal "IN3")
		(16 "In7.Cu" signal "GND3")
		(18 "In8.Cu" signal "VCC")
		(20 "In9.Cu" signal "VCC1")
		(22 "In10.Cu" signal "GND4")
		(24 "In11.Cu" signal "IN4")
		(26 "In12.Cu" signal "GND5")
		(28 "In13.Cu" signal "IN5")
		(30 "In14.Cu" signal "GND6")
		(32 "In15.Cu" signal "IN6")
		(34 "In16.Cu" signal "GND7")
		(2 "B.Cu" signal "BOTTOM")
		(9 "F.Adhes" user "F.Adhesive")
		(11 "B.Adhes" user "B.Adhesive")
		(13 "F.Paste" user "Package Geometry/Pastemask Top")
		(15 "B.Paste" user "Package Geometry/Pastemask Bottom")
		(5 "F.SilkS" user "Ref Des/Silkscreen Top")
		(7 "B.SilkS" user "Ref Des/Silkscreen Bottom")
		(1 "F.Mask" user "Board Geometry/Soldermask Top")
		(3 "B.Mask" user "Board Geometry/Soldermask Bottom")
		(17 "Dwgs.User" user "User.Drawings")
		(19 "Cmts.User" user "User.Comments")
		(21 "Eco1.User" user "User.Eco1")
		(23 "Eco2.User" user "User.Eco2")
		(25 "Edge.Cuts" user "Board Geometry/Outline")
		(27 "Margin" user)
		(31 "F.CrtYd" user "Package Geometry/Place Bound Top")
		(29 "B.CrtYd" user "Package Geometry/Place Bound Bottom")
		(35 "F.Fab" user "Ref Des/Assembly Top")
		(33 "B.Fab" user "Ref Des/Assembly Bottom")
	)
	(footprint ""
		(layer "B.Cu")
		(at 15.433294 -110.987586 90)
		(property "Reference" "C5234"
			(at 0 0 90)
			(layer "B.SilkS")
			(hide yes)
			(effects
				(font
					(size 1.27 1.27)
				)
				(justify mirror)
			)
		)
		(property "Value" ""
			(at 0 0 90)
			(layer "B.Fab")
			(effects
				(font
					(size 1.27 1.27)
				)
				(justify mirror)
			)
		)
		(duplicate_pad_numbers_are_jumpers no)
		(fp_line
			(start 0.7874 -0.4064)
			(end -0.7874 -0.4064)
			(stroke
				(width 0.1524)
				(type default)
			)
			(layer "B.SilkS")
		)
		(fp_line
			(start -0.7874 -0.4064)
			(end -0.7874 0.4064)
			(stroke
				(width 0.1524)
				(type default)
			)
			(layer "B.SilkS")
		)
		(fp_line
			(start 0.7874 0.4064)
			(end 0.7874 -0.4064)
			(stroke
				(width 0.1524)
				(type default)
			)
			(layer "B.SilkS")
		)
		(fp_line
			(start -0.7874 0.4064)
			(end 0.7874 0.4064)
			(stroke
				(width 0.1524)
				(type default)
			)
			(layer "B.SilkS")
		)
		(fp_line
			(start 0.67945 -0.305054)
			(end 0.12065 -0.305054)
			(stroke
				(width 0.1)
				(type default)
			)
			(layer "B.Fab")
		)
		(fp_line
			(start 0.12065 -0.305054)
			(end 0.12065 -0.2794)
			(stroke
				(width 0.1)
				(type default)
			)
			(layer "B.Fab")
		)
		(fp_line
			(start -0.12065 -0.3048)
			(end -0.67945 -0.3048)
			(stroke
				(width 0.1)
				(type default)
			)
			(layer "B.Fab")
		)
		(fp_line
			(start -0.67945 -0.3048)
			(end -0.67945 0.3048)
			(stroke
				(width 0.1)
				(type default)
			)
			(layer "B.Fab")
		)
		(fp_line
			(start 0.12065 -0.2794)
			(end -0.12065 -0.2794)
			(stroke
				(width 0.1)
				(type default)
			)
			(layer "B.Fab")
		)
		(fp_line
			(start -0.12065 -0.2794)
			(end -0.12065 -0.3048)
			(stroke
				(width 0.1)
				(type default)
			)
			(layer "B.Fab")
		)
		(fp_line
			(start 0.12065 0.2794)
			(end 0.12065 0.3048)
			(stroke
				(width 0.1)
				(type default)
			)
			(layer "B.Fab")
		)
		(fp_line
			(start -0.120396 0.2794)
			(end 0.12065 0.2794)
			(stroke
				(width 0.1)
				(type default)
			)
			(layer "B.Fab")
		)
		(fp_line
			(start 0.67945 0.3048)
			(end 0.67945 -0.305054)
			(stroke
				(width 0.1)
				(type default)
			)
			(layer "B.Fab")
		)
		(fp_line
			(start 0.12065 0.3048)
			(end 0.67945 0.3048)
			(stroke
				(width 0.1)
				(type default)
			)
			(layer "B.Fab")
		)
		(fp_line
			(start -0.120396 0.3048)
			(end -0.120396 0.2794)
			(stroke
				(width 0.1)
				(type default)
			)
			(layer "B.Fab")
		)
		(fp_line
			(start -0.67945 0.3048)
			(end -0.120396 0.3048)
			(stroke
				(width 0.1)
				(type default)
			)
			(layer "B.Fab")
		)
		(pad "1" smd circle
			(at 0.40005 0 270)
			(size 0 0)
			(layers "B.Cu" "B.Mask" "B.Paste")
			(net "P3V3_AUX")
		)
		(pad "2" smd circle
			(at -0.40005 0 270)
			(size 0 0)
			(layers "B.Cu" "B.Mask" "B.Paste")
			(net "GND")
		)
	)
	(footprint ""
		(layer "B.Cu")
		(at 329.119992 -65.24752 45)
		(property "Reference" "C1251"
			(at 0 0 45)
			(layer "B.SilkS")
			(hide yes)
			(effects
				(font
					(size 1.27 1.27)
				)
				(justify mirror)
			)
		)
		(property "Value" ""
			(at 0 0 45)
			(layer "B.Fab")
			(effects
				(font
					(size 1.27 1.27)
				)
				(justify mirror)
			)
		)
		(duplicate_pad_numbers_are_jumpers no)
		(fp_line
			(start -1.295492 -0.584255)
			(end -1.295492 0.584255)
			(stroke
				(width 0.1524)
				(type default)
			)
			(layer "B.SilkS")
		)
		(fp_line
			(start -1.295492 0.584255)
			(end 1.295492 0.584255)
			(stroke
				(width 0.1524)
				(type default)
			)
			(layer "B.SilkS")
		)
		(fp_line
			(start 0 -0.584076)
			(end 0 0.584076)
			(stroke
				(width 0.1524)
				(type default)
			)
			(layer "B.SilkS")
		)
		(fp_line
			(start 1.295492 -0.584255)
			(end -1.295492 -0.584255)
			(stroke
				(width 0.1524)
				(type default)
			)
			(layer "B.SilkS")
		)
		(fp_line
			(start 1.295492 0.584255)
			(end 1.295492 -0.584255)
			(stroke
				(width 0.1524)
				(type default)
			)
			(layer "B.SilkS")
		)
		(fp_line
			(start -1.193835 -0.406446)
			(end -1.193835 0.406446)
			(stroke
				(width 0.1)
				(type default)
			)
			(layer "B.Fab")
		)
		(fp_line
			(start -0.863541 -0.457275)
			(end -0.863721 -0.406446)
			(stroke
				(width 0.1)
				(type default)
			)
			(layer "B.Fab")
		)
		(fp_line
			(start -0.863721 -0.406446)
			(end -1.193835 -0.406446)
			(stroke
				(width 0.1)
				(type default)
			)
			(layer "B.Fab")
		)
		(fp_line
			(start -1.193835 0.406446)
			(end -0.863721 0.406446)
			(stroke
				(width 0.1)
				(type default)
			)
			(layer "B.Fab")
		)
		(fp_line
			(start -0.863721 0.406446)
			(end -0.863541 0.457275)
			(stroke
				(width 0.1)
				(type default)
			)
			(layer "B.Fab")
		)
		(fp_line
			(start -0.863541 0.457275)
			(end 0.863541 0.457275)
			(stroke
				(width 0.1)
				(type default)
			)
			(layer "B.Fab")
		)
		(fp_line
			(start 0.863541 -0.457275)
			(end -0.863541 -0.457275)
			(stroke
				(width 0.1)
				(type default)
			)
			(layer "B.Fab")
		)
		(fp_line
			(start 0.863721 -0.406446)
			(end 0.863541 -0.457275)
			(stroke
				(width 0.1)
				(type default)
			)
			(layer "B.Fab")
		)
		(fp_line
			(start 1.193835 -0.406446)
			(end 0.863721 -0.406446)
			(stroke
				(width 0.1)
				(type default)
			)
			(layer "B.Fab")
		)
		(fp_line
			(start 0.863721 0.406446)
			(end 1.193835 0.406446)
			(stroke
				(width 0.1)
				(type default)
			)
			(layer "B.Fab")
		)
		(fp_line
			(start 0.863541 0.457275)
			(end 0.863721 0.406446)
			(stroke
				(width 0.1)
				(type default)
			)
			(layer "B.Fab")
		)
		(fp_line
			(start 1.193835 0.406446)
			(end 1.193835 -0.406446)
			(stroke
				(width 0.1)
				(type default)
			)
			(layer "B.Fab")
		)
		(pad "1" smd rect
			(at 0.7366 0 315)
			(size 0.7112 0.8128)
			(layers "B.Cu" "B.Mask" "B.Paste")
			(net "P1V05_PCH_PLL_AUX")
		)
		(pad "2" smd rect
			(at -0.7366 0 315)
			(size 0.7112 0.8128)
			(layers "B.Cu" "B.Mask" "B.Paste")
			(net "GND")
		)
	)
)
